(kicad_pcb
	(version 20260206)
	(generator "pcbnew")
	(generator_version "10.0")
	(general
		(thickness 1.6)
		(legacy_teardrops no)
	)
	(paper "A4")
	(title_block
		(title "Wiwynn_Tioga_Pass_MB.brd")
		(comment 1 "Tioga Pass / footprints 102-109 of 4770")
	)
	(layers
		(0 "F.Cu" signal "TOP")
		(4 "In1.Cu" signal "L2GND")
		(6 "In2.Cu" signal "L3")
		(8 "In3.Cu" signal "L4GND")
		(10 "In4.Cu" signal "L5")
		(12 "In5.Cu" signal "L6GND")
		(14 "In6.Cu" signal "L7VCC")
		(16 "In7.Cu" signal "L8VCC")
		(18 "In8.Cu" signal "L9GND")
		(20 "In9.Cu" signal "L10")
		(22 "In10.Cu" signal "L11GND")
		(24 "In11.Cu" signal "L12")
		(26 "In12.Cu" signal "L13GND")
		(2 "B.Cu" signal "BOTTOM")
		(9 "F.Adhes" user "F.Adhesive")
		(11 "B.Adhes" user "B.Adhesive")
		(13 "F.Paste" user "Package Geometry/Pastemask Top")
		(15 "B.Paste" user "Package Geometry/Pastemask Bottom")
		(5 "F.SilkS" user "Ref Des/Silkscreen Top")
		(7 "B.SilkS" user "Ref Des/Silkscreen Bottom")
		(1 "F.Mask" user "Board Geometry/Soldermask Top")
		(3 "B.Mask" user "Board Geometry/Soldermask Bottom")
		(17 "Dwgs.User" user "User.Drawings")
		(19 "Cmts.User" user "User.Comments")
		(21 "Eco1.User" user "User.Eco1")
		(23 "Eco2.User" user "User.Eco2")
		(25 "Edge.Cuts" user "Board Geometry/Outline")
		(27 "Margin" user)
		(31 "F.CrtYd" user "Package Geometry/Place Bound Top")
		(29 "B.CrtYd" user "Package Geometry/Place Bound Bottom")
		(35 "F.Fab" user "Ref Des/Assembly Top")
		(33 "B.Fab" user "Ref Des/Assembly Bottom")
	)
	(footprint ""
		(layer "F.Cu")
		(at 183.134 -132.207 90)
		(property "Reference" "C6M5"
			(at 1.47828 0.78994 0)
			(unlocked yes)
			(layer "F.SilkS")
			(effects
				(font
					(size 0.4064 0.254)
					(thickness 0.1524)
				)
			)
		)
		(property "Value" ""
			(at 0 0 90)
			(layer "F.Fab")
			(effects
				(font
					(size 1.27 1.27)
				)
			)
		)
		(duplicate_pad_numbers_are_jumpers no)
		(fp_poly
			(pts
				(xy -0.7239 -0.2159) (xy 0.7239 -0.2159) (xy 0.7239 1.9939) (xy -0.7239 1.9939)
			)
			(stroke
				(width 0)
				(type default)
			)
			(fill no)
			(layer "F.CrtYd")
		)
		(fp_line
			(start 0.7239 -0.2159)
			(end -0.7239 -0.2159)
			(stroke
				(width 0.1)
				(type default)
			)
			(layer "F.Fab")
		)
		(fp_line
			(start -0.7239 -0.2159)
			(end -0.7239 1.9939)
			(stroke
				(width 0.1)
				(type default)
			)
			(layer "F.Fab")
		)
		(fp_line
			(start 0.7239 1.9939)
			(end 0.7239 -0.2159)
			(stroke
				(width 0.1)
				(type default)
			)
			(layer "F.Fab")
		)
		(fp_line
			(start -0.7239 1.9939)
			(end 0.7239 1.9939)
			(stroke
				(width 0.1)
				(type default)
			)
			(layer "F.Fab")
		)
		(pad "1" smd rect
			(at 0 0 90)
			(size 1.27 1.016)
			(layers "F.Cu" "F.Mask" "F.Paste")
			(net "VR_FET_SW_P12V_STBY_PVPP_KLM")
		)
		(pad "2" smd rect
			(at 0 1.778 90)
			(size 1.27 1.016)
			(layers "F.Cu" "F.Mask" "F.Paste")
			(net "GND")
		)
		(zone
			(layer "F.Cu")
			(hatch none 0.5)
			(connect_pads
				(clearance 0)
			)
			(min_thickness 0.25)
			(keepout
				(tracks not_allowed)
				(vias allowed)
				(pads allowed)
				(copperpour not_allowed)
				(footprints allowed)
			)
			(placement
				(enabled no)
				(sheetname "")
			)
			(fill
				(thermal_gap 0.5)
				(thermal_bridge_width 0.5)
				(island_removal_mode 0)
			)
			(polygon
				(pts
					(xy 183.642 -131.572) (xy 183.642 -132.842) (xy 184.404 -132.842) (xy 184.404 -131.572)
				)
			)
		)
	)
	(footprint ""
		(layer "F.Cu")
		(at 39.330122 -106.415586 -90)
		(property "Reference" "R9N2"
			(at 0 0 270)
			(layer "F.SilkS")
			(hide yes)
			(effects
				(font
					(size 1.27 1.27)
				)
			)
		)
		(property "Value" ""
			(at 0 0 270)
			(layer "F.Fab")
			(effects
				(font
					(size 1.27 1.27)
				)
			)
		)
		(duplicate_pad_numbers_are_jumpers no)
		(fp_poly
			(pts
				(xy -0.2794 -0.1016) (xy 0.2794 -0.1016) (xy 0.2794 0.9906) (xy -0.2794 0.9906)
			)
			(stroke
				(width 0)
				(type default)
			)
			(fill no)
			(layer "F.CrtYd")
		)
		(fp_line
			(start -0.2794 0.9906)
			(end 0.2794 0.9906)
			(stroke
				(width 0.1)
				(type default)
			)
			(layer "F.Fab")
		)
		(fp_line
			(start 0.2794 0.9906)
			(end 0.2794 -0.1016)
			(stroke
				(width 0.1)
				(type default)
			)
			(layer "F.Fab")
		)
		(fp_line
			(start -0.2794 -0.1016)
			(end -0.2794 0.9906)
			(stroke
				(width 0.1)
				(type default)
			)
			(layer "F.Fab")
		)
		(fp_line
			(start 0.2794 -0.1016)
			(end -0.2794 -0.1016)
			(stroke
				(width 0.1)
				(type default)
			)
			(layer "F.Fab")
		)
		(pad "1" smd rect
			(at 0 0 270)
			(size 0.508 0.508)
			(layers "F.Cu" "F.Mask" "F.Paste")
			(net "PVCCIO_CPU1")
		)
		(pad "2" smd rect
			(at 0 0.889 270)
			(size 0.508 0.508)
			(layers "F.Cu" "F.Mask" "F.Paste")
			(net "SVID_DIO1_CPU1_R")
		)
		(zone
			(layer "F.Cu")
			(hatch none 0.5)
			(connect_pads
				(clearance 0)
			)
			(min_thickness 0.25)
			(keepout
				(tracks not_allowed)
				(vias allowed)
				(pads allowed)
				(copperpour not_allowed)
				(footprints allowed)
			)
			(placement
				(enabled no)
				(sheetname "")
			)
			(fill
				(thermal_gap 0.5)
				(thermal_bridge_width 0.5)
				(island_removal_mode 0)
			)
			(polygon
				(pts
					(xy 38.695122 -106.669586) (xy 38.695122 -106.161586) (xy 39.076122 -106.161586) (xy 39.076122 -106.669586)
				)
			)
		)
		(zone
			(layer "F.Cu")
			(hatch none 0.5)
			(connect_pads
				(clearance 0)
			)
			(min_thickness 0.25)
			(keepout
				(tracks allowed)
				(vias not_allowed)
				(pads allowed)
				(copperpour not_allowed)
				(footprints allowed)
			)
			(placement
				(enabled no)
				(sheetname "")
			)
			(fill
				(thermal_gap 0.5)
				(thermal_bridge_width 0.5)
				(island_removal_mode 0)
			)
			(polygon
				(pts
					(xy 39.076122 -106.669586) (xy 39.076122 -106.161586) (xy 38.695122 -106.161586) (xy 38.695122 -106.669586)
				)
			)
		)
	)
	(footprint ""
		(layer "F.Cu")
		(at 379.4125 -36.5506)
		(property "Reference" "R8F35"
			(at 0 0 0)
			(layer "F.SilkS")
			(hide yes)
			(effects
				(font
					(size 1.27 1.27)
				)
			)
		)
		(property "Value" ""
			(at 0 0 0)
			(layer "F.Fab")
			(effects
				(font
					(size 1.27 1.27)
				)
			)
		)
		(duplicate_pad_numbers_are_jumpers no)
		(fp_poly
			(pts
				(xy -0.2794 -0.1016) (xy 0.2794 -0.1016) (xy 0.2794 0.9906) (xy -0.2794 0.9906)
			)
			(stroke
				(width 0)
				(type default)
			)
			(fill no)
			(layer "F.CrtYd")
		)
		(fp_line
			(start -0.2794 -0.1016)
			(end -0.2794 0.9906)
			(stroke
				(width 0.1)
				(type default)
			)
			(layer "F.Fab")
		)
		(fp_line
			(start -0.2794 0.9906)
			(end 0.2794 0.9906)
			(stroke
				(width 0.1)
				(type default)
			)
			(layer "F.Fab")
		)
		(fp_line
			(start 0.2794 -0.1016)
			(end -0.2794 -0.1016)
			(stroke
				(width 0.1)
				(type default)
			)
			(layer "F.Fab")
		)
		(fp_line
			(start 0.2794 0.9906)
			(end 0.2794 -0.1016)
			(stroke
				(width 0.1)
				(type default)
			)
			(layer "F.Fab")
		)
		(pad "1" smd rect
			(at 0 0)
			(size 0.508 0.508)
			(layers "F.Cu" "F.Mask" "F.Paste")
			(net "PU_SPI_BMC_BT_WP_N")
		)
		(pad "2" smd rect
			(at 0 0.889)
			(size 0.508 0.508)
			(layers "F.Cu" "F.Mask" "F.Paste")
			(net "GND")
		)
		(zone
			(layer "F.Cu")
			(hatch none 0.5)
			(connect_pads
				(clearance 0)
			)
			(min_thickness 0.25)
			(keepout
				(tracks allowed)
				(vias not_allowed)
				(pads allowed)
				(copperpour not_allowed)
				(footprints allowed)
			)
			(placement
				(enabled no)
				(sheetname "")
			)
			(fill
				(thermal_gap 0.5)
				(thermal_bridge_width 0.5)
				(island_removal_mode 0)
			)
			(polygon
				(pts
					(xy 379.1585 -36.2966) (xy 379.6665 -36.2966) (xy 379.6665 -35.9156) (xy 379.1585 -35.9156)
				)
			)
		)
		(zone
			(layer "F.Cu")
			(hatch none 0.5)
			(connect_pads
				(clearance 0)
			)
			(min_thickness 0.25)
			(keepout
				(tracks not_allowed)
				(vias allowed)
				(pads allowed)
				(copperpour not_allowed)
				(footprints allowed)
			)
			(placement
				(enabled no)
				(sheetname "")
			)
			(fill
				(thermal_gap 0.5)
				(thermal_bridge_width 0.5)
				(island_removal_mode 0)
			)
			(polygon
				(pts
					(xy 379.1585 -35.9156) (xy 379.6665 -35.9156) (xy 379.6665 -36.2966) (xy 379.1585 -36.2966)
				)
			)
		)
	)
	(footprint ""
		(layer "F.Cu")
		(at 29.495496 -27.150822 180)
		(property "Reference" "R12W14"
			(at 1.01473 0.656336 90)
			(unlocked yes)
			(layer "F.SilkS")
			(effects
				(font
					(size 0.4064 0.254)
					(thickness 0.1524)
				)
			)
		)
		(property "Value" ""
			(at 0 0 180)
			(layer "F.Fab")
			(effects
				(font
					(size 1.27 1.27)
				)
			)
		)
		(duplicate_pad_numbers_are_jumpers no)
		(fp_poly
			(pts
				(xy -0.4953 -0.2032) (xy 0.4953 -0.2032) (xy 0.4953 1.6002) (xy -0.4953 1.6002)
			)
			(stroke
				(width 0)
				(type default)
			)
			(fill no)
			(layer "F.CrtYd")
		)
		(fp_line
			(start 0.4953 1.6002)
			(end -0.4953 1.6002)
			(stroke
				(width 0.1)
				(type default)
			)
			(layer "F.Fab")
		)
		(fp_line
			(start 0.4953 -0.2032)
			(end 0.4953 1.6002)
			(stroke
				(width 0.1)
				(type default)
			)
			(layer "F.Fab")
		)
		(fp_line
			(start -0.4953 1.6002)
			(end -0.4953 -0.2032)
			(stroke
				(width 0.1)
				(type default)
			)
			(layer "F.Fab")
		)
		(fp_line
			(start -0.4953 -0.2032)
			(end 0.4953 -0.2032)
			(stroke
				(width 0.1)
				(type default)
			)
			(layer "F.Fab")
		)
		(pad "1" smd rect
			(at 0 0 180)
			(size 0.762 0.889)
			(layers "F.Cu" "F.Mask" "F.Paste")
			(net "P12V_NVDIMM_GHJ")
		)
		(pad "2" smd rect
			(at 0 1.397 180)
			(size 0.762 0.889)
			(layers "F.Cu" "F.Mask" "F.Paste")
			(net "PWRGD_PVDDQ_GHJ_N")
		)
		(zone
			(layer "F.Cu")
			(hatch none 0.5)
			(connect_pads
				(clearance 0)
			)
			(min_thickness 0.25)
			(keepout
				(tracks allowed)
				(vias not_allowed)
				(pads allowed)
				(copperpour not_allowed)
				(footprints allowed)
			)
			(placement
				(enabled no)
				(sheetname "")
			)
			(fill
				(thermal_gap 0.5)
				(thermal_bridge_width 0.5)
				(island_removal_mode 0)
			)
			(polygon
				(pts
					(xy 29.114496 -28.103322) (xy 29.114496 -27.595322) (xy 29.876496 -27.595322) (xy 29.876496 -28.103322)
				)
			)
		)
		(zone
			(layer "F.Cu")
			(hatch none 0.5)
			(connect_pads
				(clearance 0)
			)
			(min_thickness 0.25)
			(keepout
				(tracks not_allowed)
				(vias allowed)
				(pads allowed)
				(copperpour not_allowed)
				(footprints allowed)
			)
			(placement
				(enabled no)
				(sheetname "")
			)
			(fill
				(thermal_gap 0.5)
				(thermal_bridge_width 0.5)
				(island_removal_mode 0)
			)
			(polygon
				(pts
					(xy 29.876496 -28.103322) (xy 29.114496 -28.103322) (xy 29.114496 -27.595322) (xy 29.876496 -27.595322)
				)
			)
		)
	)
	(footprint ""
		(layer "F.Cu")
		(at 28.7528 -103.7844 90)
		(property "Reference" "R1C34"
			(at 0 0 90)
			(layer "F.SilkS")
			(hide yes)
			(effects
				(font
					(size 1.27 1.27)
				)
			)
		)
		(property "Value" ""
			(at 0 0 90)
			(layer "F.Fab")
			(effects
				(font
					(size 1.27 1.27)
				)
			)
		)
		(duplicate_pad_numbers_are_jumpers no)
		(fp_poly
			(pts
				(xy -0.2794 -0.1016) (xy 0.2794 -0.1016) (xy 0.2794 0.9906) (xy -0.2794 0.9906)
			)
			(stroke
				(width 0)
				(type default)
			)
			(fill no)
			(layer "F.CrtYd")
		)
		(fp_line
			(start 0.2794 -0.1016)
			(end -0.2794 -0.1016)
			(stroke
				(width 0.1)
				(type default)
			)
			(layer "F.Fab")
		)
		(fp_line
			(start -0.2794 -0.1016)
			(end -0.2794 0.9906)
			(stroke
				(width 0.1)
				(type default)
			)
			(layer "F.Fab")
		)
		(fp_line
			(start 0.2794 0.9906)
			(end 0.2794 -0.1016)
			(stroke
				(width 0.1)
				(type default)
			)
			(layer "F.Fab")
		)
		(fp_line
			(start -0.2794 0.9906)
			(end 0.2794 0.9906)
			(stroke
				(width 0.1)
				(type default)
			)
			(layer "F.Fab")
		)
		(pad "1" smd rect
			(at 0 0 90)
			(size 0.508 0.508)
			(layers "F.Cu" "F.Mask" "F.Paste")
			(net "P3V3_STBY")
		)
		(pad "2" smd rect
			(at 0 0.889 90)
			(size 0.508 0.508)
			(layers "F.Cu" "F.Mask" "F.Paste")
			(net "PU_PIROM_CPU1_ADDR0")
		)
		(zone
			(layer "F.Cu")
			(hatch none 0.5)
			(connect_pads
				(clearance 0)
			)
			(min_thickness 0.25)
			(keepout
				(tracks allowed)
				(vias not_allowed)
				(pads allowed)
				(copperpour not_allowed)
				(footprints allowed)
			)
			(placement
				(enabled no)
				(sheetname "")
			)
			(fill
				(thermal_gap 0.5)
				(thermal_bridge_width 0.5)
				(island_removal_mode 0)
			)
			(polygon
				(pts
					(xy 29.0068 -103.5304) (xy 29.0068 -104.0384) (xy 29.3878 -104.0384) (xy 29.3878 -103.5304)
				)
			)
		)
		(zone
			(layer "F.Cu")
			(hatch none 0.5)
			(connect_pads
				(clearance 0)
			)
			(min_thickness 0.25)
			(keepout
				(tracks not_allowed)
				(vias allowed)
				(pads allowed)
				(copperpour not_allowed)
				(footprints allowed)
			)
			(placement
				(enabled no)
				(sheetname "")
			)
			(fill
				(thermal_gap 0.5)
				(thermal_bridge_width 0.5)
				(island_removal_mode 0)
			)
			(polygon
				(pts
					(xy 29.3878 -103.5304) (xy 29.3878 -104.0384) (xy 29.0068 -104.0384) (xy 29.0068 -103.5304)
				)
			)
		)
	)
	(footprint ""
		(layer "F.Cu")
		(at 388.2263 -68.8848 180)
		(property "Reference" "C22W9"
			(at 0 0 180)
			(layer "F.SilkS")
			(hide yes)
			(effects
				(font
					(size 1.27 1.27)
				)
			)
		)
		(property "Value" "*"
			(at -0.0762 -6.2357 180)
			(unlocked yes)
			(layer "F.Fab")
			(hide yes)
			(effects
				(font
					(size 1.27 1.016)
					(thickness 0.1524)
				)
			)
		)
		(property "Device Type" "SC22U16V5MX-4-GP_SMD-BCG5-SC22A"
			(at -0.0762 -8.2677 180)
			(unlocked yes)
			(layer "F.Fab")
			(hide yes)
			(effects
				(font
					(size 1.27 1.016)
					(thickness 0.1524)
				)
			)
		)
		(duplicate_pad_numbers_are_jumpers no)
		(fp_line
			(start 0.635 0)
			(end -0.635 0)
			(stroke
				(width 0.508)
				(type default)
			)
			(layer "F.SilkS")
		)
		(fp_rect
			(start -0.9652 1.778)
			(end 0.9652 -1.778)
			(stroke
				(width 0)
				(type default)
			)
			(fill no)
			(layer "F.CrtYd")
		)
		(fp_poly
			(pts
				(xy -0.9652 -1.778) (xy 0.9652 -1.778) (xy 0.9652 1.778) (xy -0.9652 1.778)
			)
			(stroke
				(width 0)
				(type default)
			)
			(fill no)
			(layer "F.Fab")
		)
		(pad "1" smd rect
			(at 0 -0.9652 180)
			(size 1.397 1.143)
			(layers "F.Cu" "F.Mask" "F.Paste")
			(net "VR_FET_SW_P5V_STBY_PVIN")
		)
		(pad "2" smd rect
			(at 0 0.9652 180)
			(size 1.397 1.143)
			(layers "F.Cu" "F.Mask" "F.Paste")
			(net "GND")
		)
	)
	(footprint ""
		(layer "F.Cu")
		(at 348.488 -104.267 180)
		(property "Reference" "C22W28"
			(at 0 0 180)
			(layer "F.SilkS")
			(hide yes)
			(effects
				(font
					(size 1.27 1.27)
				)
			)
		)
		(property "Value" "*"
			(at -0.0762 -6.2357 180)
			(unlocked yes)
			(layer "F.Fab")
			(hide yes)
			(effects
				(font
					(size 1.27 1.016)
					(thickness 0.1524)
				)
			)
		)
		(property "Device Type" "SC22U16V5MX-4-GP_SMD-BCG5-SC22A"
			(at -0.0762 -8.2677 180)
			(unlocked yes)
			(layer "F.Fab")
			(hide yes)
			(effects
				(font
					(size 1.27 1.016)
					(thickness 0.1524)
				)
			)
		)
		(duplicate_pad_numbers_are_jumpers no)
		(fp_line
			(start 0.635 0)
			(end -0.635 0)
			(stroke
				(width 0.508)
				(type default)
			)
			(layer "F.SilkS")
		)
		(fp_rect
			(start -0.9652 1.778)
			(end 0.9652 -1.778)
			(stroke
				(width 0)
				(type default)
			)
			(fill no)
			(layer "F.CrtYd")
		)
		(fp_poly
			(pts
				(xy -0.9652 -1.778) (xy 0.9652 -1.778) (xy 0.9652 1.778) (xy -0.9652 1.778)
			)
			(stroke
				(width 0)
				(type default)
			)
			(fill no)
			(layer "F.Fab")
		)
		(pad "1" smd rect
			(at 0 -0.9652 180)
			(size 1.397 1.143)
			(layers "F.Cu" "F.Mask" "F.Paste")
			(net "VR_FET_SW_P12V_STBY_PVCCIO_CPU0")
		)
		(pad "2" smd rect
			(at 0 0.9652 180)
			(size 1.397 1.143)
			(layers "F.Cu" "F.Mask" "F.Paste")
			(net "GND")
		)
	)
	(footprint ""
		(layer "F.Cu")
		(at 401.472146 -36.458652 90)
		(property "Reference" "R6W18"
			(at -0.8382 -0.67818 90)
			(unlocked yes)
			(layer "F.SilkS")
			(effects
				(font
					(size 0.4064 0.254)
					(thickness 0.1524)
				)
				(justify left)
			)
		)
		(property "Value" ""
			(at 0 0 90)
			(layer "F.Fab")
			(effects
				(font
					(size 1.27 1.27)
				)
			)
		)
		(duplicate_pad_numbers_are_jumpers no)
		(fp_poly
			(pts
				(xy -0.2794 -0.1016) (xy 0.2794 -0.1016) (xy 0.2794 0.9906) (xy -0.2794 0.9906)
			)
			(stroke
				(width 0)
				(type default)
			)
			(fill no)
			(layer "F.CrtYd")
		)
		(fp_line
			(start 0.2794 -0.1016)
			(end -0.2794 -0.1016)
			(stroke
				(width 0.1)
				(type default)
			)
			(layer "F.Fab")
		)
		(fp_line
			(start -0.2794 -0.1016)
			(end -0.2794 0.9906)
			(stroke
				(width 0.1)
				(type default)
			)
			(layer "F.Fab")
		)
		(fp_line
			(start 0.2794 0.9906)
			(end 0.2794 -0.1016)
			(stroke
				(width 0.1)
				(type default)
			)
			(layer "F.Fab")
		)
		(fp_line
			(start -0.2794 0.9906)
			(end 0.2794 0.9906)
			(stroke
				(width 0.1)
				(type default)
			)
			(layer "F.Fab")
		)
		(pad "1" smd rect
			(at 0 0 90)
			(size 0.508 0.508)
			(layers "F.Cu" "F.Mask" "F.Paste")
			(net "SMB_DEBUG_STBY_LVC3_SDA")
		)
		(pad "2" smd rect
			(at 0 0.889 90)
			(size 0.508 0.508)
			(layers "F.Cu" "F.Mask" "F.Paste")
			(net "SMB_DEBUG_STBY_LVC3_SDA_R")
		)
		(zone
			(layer "F.Cu")
			(hatch none 0.5)
			(connect_pads
				(clearance 0)
			)
			(min_thickness 0.25)
			(keepout
				(tracks allowed)
				(vias not_allowed)
				(pads allowed)
				(copperpour not_allowed)
				(footprints allowed)
			)
			(placement
				(enabled no)
				(sheetname "")
			)
			(fill
				(thermal_gap 0.5)
				(thermal_bridge_width 0.5)
				(island_removal_mode 0)
			)
			(polygon
				(pts
					(xy 401.726146 -36.204652) (xy 401.726146 -36.712652) (xy 402.107146 -36.712652) (xy 402.107146 -36.204652)
				)
			)
		)
		(zone
			(layer "F.Cu")
			(hatch none 0.5)
			(connect_pads
				(clearance 0)
			)
			(min_thickness 0.25)
			(keepout
				(tracks not_allowed)
				(vias allowed)
				(pads allowed)
				(copperpour not_allowed)
				(footprints allowed)
			)
			(placement
				(enabled no)
				(sheetname "")
			)
			(fill
				(thermal_gap 0.5)
				(thermal_bridge_width 0.5)
				(island_removal_mode 0)
			)
			(polygon
				(pts
					(xy 402.107146 -36.204652) (xy 402.107146 -36.712652) (xy 401.726146 -36.712652) (xy 401.726146 -36.204652)
				)
			)
		)
	)
)
